# T6G (Grand Teton) — schematic netlist excerpt (pin names and nets, part order shuffled) for the footprints in the layout excerpt that follows; sources: Cadence DE-HDL packaged netlist, KiCad conversion of 04192023_DAF0TMB3IC0_F0TG_MB_C_brd_V02_OCP.brd

C1520  Q_CAP  0.01UF 50V 10% EMPTY  pkg C0402  page 174 : A = JTAG_CPU0_TDI ; B = GND

(kicad_pcb
	(version 20260206)
	(generator "pcbnew")
	(generator_version "10.0")
	(general
		(thickness 1.6)
		(legacy_teardrops no)
	)
	(paper "A4")
	(title_block
		(title "04192023_DAF0TMB3IC0_F0TG_MB_C_brd_V02_OCP.brd")
		(comment 1 "Grand Teton / footprints 1752-1752 of 8354")
	)
	(layers
		(0 "F.Cu" signal "TOP")
		(4 "In1.Cu" signal "GND")
		(6 "In2.Cu" signal "IN1")
		(8 "In3.Cu" signal "GND1")
		(10 "In4.Cu" signal "IN2")
		(12 "In5.Cu" signal "GND2")
		(14 "In6.Cu" signal "IN3")
		(16 "In7.Cu" signal "GND3")
		(18 "In8.Cu" signal "VCC")
		(20 "In9.Cu" signal "VCC1")
		(22 "In10.Cu" signal "GND4")
		(24 "In11.Cu" signal "IN4")
		(26 "In12.Cu" signal "GND5")
		(28 "In13.Cu" signal "IN5")
		(30 "In14.Cu" signal "GND6")
		(32 "In15.Cu" signal "IN6")
		(34 "In16.Cu" signal "GND7")
		(2 "B.Cu" signal "BOTTOM")
		(9 "F.Adhes" user "F.Adhesive")
		(11 "B.Adhes" user "B.Adhesive")
		(13 "F.Paste" user "Package Geometry/Pastemask Top")
		(15 "B.Paste" user "Package Geometry/Pastemask Bottom")
		(5 "F.SilkS" user "Ref Des/Silkscreen Top")
		(7 "B.SilkS" user "Ref Des/Silkscreen Bottom")
		(1 "F.Mask" user "Board Geometry/Soldermask Top")
		(3 "B.Mask" user "Board Geometry/Soldermask Bottom")
		(17 "Dwgs.User" user "User.Drawings")
		(19 "Cmts.User" user "User.Comments")
		(21 "Eco1.User" user "User.Eco1")
		(23 "Eco2.User" user "User.Eco2")
		(25 "Edge.Cuts" user "Board Geometry/Outline")
		(27 "Margin" user)
		(31 "F.CrtYd" user "Package Geometry/Place Bound Top")
		(29 "B.CrtYd" user "Package Geometry/Place Bound Bottom")
		(35 "F.Fab" user "Ref Des/Assembly Top")
		(33 "B.Fab" user "Ref Des/Assembly Bottom")
	)
	(footprint ""
		(layer "F.Cu")
		(at 240.431574 -149.965918 180)
		(property "Reference" "C1520"
			(at 0 0 180)
			(layer "F.SilkS")
			(hide yes)
			(effects
				(font
					(size 1.27 1.27)
				)
			)
		)
		(property "Value" ""
			(at 0 0 180)
			(layer "F.Fab")
			(effects
				(font
					(size 1.27 1.27)
				)
			)
		)
		(duplicate_pad_numbers_are_jumpers no)
		(fp_line
			(start 0.7874 0.4064)
			(end -0.7874 0.4064)
			(stroke
				(width 0.1524)
				(type default)
			)
			(layer "F.SilkS")
		)
		(fp_line
			(start 0.7874 -0.4064)
			(end 0.7874 0.4064)
			(stroke
				(width 0.1524)
				(type default)
			)
			(layer "F.SilkS")
		)
		(fp_line
			(start -0.7874 0.4064)
			(end -0.7874 -0.4064)
			(stroke
				(width 0.1524)
				(type default)
			)
			(layer "F.SilkS")
		)
		(fp_line
			(start -0.7874 -0.4064)
			(end 0.7874 -0.4064)
			(stroke
				(width 0.1524)
				(type default)
			)
			(layer "F.SilkS")
		)
		(fp_line
			(start 0.67945 0.3048)
			(end 0.120396 0.3048)
			(stroke
				(width 0.1)
				(type default)
			)
			(layer "F.Fab")
		)
		(fp_line
			(start 0.67945 -0.3048)
			(end 0.67945 0.3048)
			(stroke
				(width 0.1)
				(type default)
			)
			(layer "F.Fab")
		)
		(fp_line
			(start 0.12065 -0.2794)
			(end 0.12065 -0.3048)
			(stroke
				(width 0.1)
				(type default)
			)
			(layer "F.Fab")
		)
		(fp_line
			(start 0.12065 -0.3048)
			(end 0.67945 -0.3048)
			(stroke
				(width 0.1)
				(type default)
			)
			(layer "F.Fab")
		)
		(fp_line
			(start 0.120396 0.3048)
			(end 0.120396 0.2794)
			(stroke
				(width 0.1)
				(type default)
			)
			(layer "F.Fab")
		)
		(fp_line
			(start 0.120396 0.2794)
			(end -0.12065 0.2794)
			(stroke
				(width 0.1)
				(type default)
			)
			(layer "F.Fab")
		)
		(fp_line
			(start -0.12065 0.3048)
			(end -0.67945 0.3048)
			(stroke
				(width 0.1)
				(type default)
			)
			(layer "F.Fab")
		)
		(fp_line
			(start -0.12065 0.2794)
			(end -0.12065 0.3048)
			(stroke
				(width 0.1)
				(type default)
			)
			(layer "F.Fab")
		)
		(fp_line
			(start -0.12065 -0.2794)
			(end 0.12065 -0.2794)
			(stroke
				(width 0.1)
				(type default)
			)
			(layer "F.Fab")
		)
		(fp_line
			(start -0.12065 -0.305054)
			(end -0.12065 -0.2794)
			(stroke
				(width 0.1)
				(type default)
			)
			(layer "F.Fab")
		)
		(fp_line
			(start -0.67945 0.3048)
			(end -0.67945 -0.305054)
			(stroke
				(width 0.1)
				(type default)
			)
			(layer "F.Fab")
		)
		(fp_line
			(start -0.67945 -0.305054)
			(end -0.12065 -0.305054)
			(stroke
				(width 0.1)
				(type default)
			)
			(layer "F.Fab")
		)
		(pad "1" smd circle
			(at -0.40005 0 180)
			(size 0 0)
			(layers "F.Cu" "F.Mask" "F.Paste")
			(net "JTAG_CPU0_TDI")
		)
		(pad "2" smd circle
			(at 0.40005 0 180)
			(size 0 0)
			(layers "F.Cu" "F.Mask" "F.Paste")
			(net "GND")
		)
	)
)
